(kicad_pcb
	(version 20260206)
	(generator "pcbnew")
	(generator_version "10.0")
	(general
		(thickness 1.6)
		(legacy_teardrops no)
	)
	(paper "A4")
	(title_block
		(title "12092022_DA0F0TFB6D0_F0T_FAN_BOARD_MP5048_D_brd_v02_OCP.brd")
		(comment 1 "Grand Teton / footprints 8-15 of 924")
	)
	(layers
		(0 "F.Cu" signal "TOP")
		(4 "In1.Cu" signal "GND")
		(6 "In2.Cu" signal "IN1")
		(8 "In3.Cu" signal "IN2")
		(10 "In4.Cu" signal "GND1")
		(2 "B.Cu" signal "BOTTOM")
		(9 "F.Adhes" user "F.Adhesive")
		(11 "B.Adhes" user "B.Adhesive")
		(13 "F.Paste" user "Package Geometry/Pastemask Top")
		(15 "B.Paste" user "Package Geometry/Pastemask Bottom")
		(5 "F.SilkS" user "Ref Des/Silkscreen Top")
		(7 "B.SilkS" user "Ref Des/Silkscreen Bottom")
		(1 "F.Mask" user "Board Geometry/Soldermask Top")
		(3 "B.Mask" user "Board Geometry/Soldermask Bottom")
		(17 "Dwgs.User" user "User.Drawings")
		(19 "Cmts.User" user "User.Comments")
		(21 "Eco1.User" user "User.Eco1")
		(23 "Eco2.User" user "User.Eco2")
		(25 "Edge.Cuts" user "Board Geometry/Outline")
		(27 "Margin" user)
		(31 "F.CrtYd" user "Package Geometry/Place Bound Top")
		(29 "B.CrtYd" user "Package Geometry/Place Bound Bottom")
		(35 "F.Fab" user "Ref Des/Assembly Top")
		(33 "B.Fab" user "Ref Des/Assembly Bottom")
	)
	(footprint ""
		(layer "F.Cu")
		(at 21.727668 -264.724388)
		(property "Reference" "ME5"
			(at 0 0 0)
			(layer "F.SilkS")
			(hide yes)
			(effects
				(font
					(size 1.27 1.27)
				)
			)
		)
		(property "Value" ""
			(at 0 0 0)
			(layer "F.Fab")
			(effects
				(font
					(size 1.27 1.27)
				)
			)
		)
		(duplicate_pad_numbers_are_jumpers no)
	)
	(footprint ""
		(layer "F.Cu")
		(at 2.794 -188.214)
		(property "Reference" "R316"
			(at 0 0 0)
			(layer "F.SilkS")
			(hide yes)
			(effects
				(font
					(size 1.27 1.27)
				)
			)
		)
		(property "Value" ""
			(at 0 0 0)
			(layer "F.Fab")
			(effects
				(font
					(size 1.27 1.27)
				)
			)
		)
		(duplicate_pad_numbers_are_jumpers no)
		(fp_line
			(start -0.7874 -0.4064)
			(end 0.7874 -0.4064)
			(stroke
				(width 0.1524)
				(type default)
			)
			(layer "F.SilkS")
		)
		(fp_line
			(start -0.7874 0.4064)
			(end -0.7874 -0.4064)
			(stroke
				(width 0.1524)
				(type default)
			)
			(layer "F.SilkS")
		)
		(fp_line
			(start 0.7874 -0.4064)
			(end 0.7874 0.4064)
			(stroke
				(width 0.1524)
				(type default)
			)
			(layer "F.SilkS")
		)
		(fp_line
			(start 0.7874 0.4064)
			(end -0.7874 0.4064)
			(stroke
				(width 0.1524)
				(type default)
			)
			(layer "F.SilkS")
		)
		(fp_line
			(start -0.67945 -0.305054)
			(end -0.12065 -0.305054)
			(stroke
				(width 0.1)
				(type default)
			)
			(layer "F.Fab")
		)
		(fp_line
			(start -0.67945 0.3048)
			(end -0.67945 -0.305054)
			(stroke
				(width 0.1)
				(type default)
			)
			(layer "F.Fab")
		)
		(fp_line
			(start -0.12065 -0.305054)
			(end -0.12065 -0.2794)
			(stroke
				(width 0.1)
				(type default)
			)
			(layer "F.Fab")
		)
		(fp_line
			(start -0.12065 -0.2794)
			(end 0.12065 -0.2794)
			(stroke
				(width 0.1)
				(type default)
			)
			(layer "F.Fab")
		)
		(fp_line
			(start -0.12065 0.2794)
			(end -0.12065 0.3048)
			(stroke
				(width 0.1)
				(type default)
			)
			(layer "F.Fab")
		)
		(fp_line
			(start -0.12065 0.3048)
			(end -0.67945 0.3048)
			(stroke
				(width 0.1)
				(type default)
			)
			(layer "F.Fab")
		)
		(fp_line
			(start 0.120396 0.2794)
			(end -0.12065 0.2794)
			(stroke
				(width 0.1)
				(type default)
			)
			(layer "F.Fab")
		)
		(fp_line
			(start 0.120396 0.3048)
			(end 0.120396 0.2794)
			(stroke
				(width 0.1)
				(type default)
			)
			(layer "F.Fab")
		)
		(fp_line
			(start 0.12065 -0.3048)
			(end 0.67945 -0.3048)
			(stroke
				(width 0.1)
				(type default)
			)
			(layer "F.Fab")
		)
		(fp_line
			(start 0.12065 -0.2794)
			(end 0.12065 -0.3048)
			(stroke
				(width 0.1)
				(type default)
			)
			(layer "F.Fab")
		)
		(fp_line
			(start 0.67945 -0.3048)
			(end 0.67945 0.3048)
			(stroke
				(width 0.1)
				(type default)
			)
			(layer "F.Fab")
		)
		(fp_line
			(start 0.67945 0.3048)
			(end 0.120396 0.3048)
			(stroke
				(width 0.1)
				(type default)
			)
			(layer "F.Fab")
		)
		(pad "1" smd circle
			(at -0.40005 0)
			(size 0 0)
			(layers "F.Cu" "F.Mask" "F.Paste")
			(net "GND")
		)
		(pad "2" smd circle
			(at 0.40005 0)
			(size 0 0)
			(layers "F.Cu" "F.Mask" "F.Paste")
			(net "FRU_ADDR1")
		)
	)
	(footprint ""
		(layer "F.Cu")
		(at 18.542 -209.169 180)
		(property "Reference" "R5536"
			(at 0 0 180)
			(layer "F.SilkS")
			(hide yes)
			(effects
				(font
					(size 1.27 1.27)
				)
			)
		)
		(property "Value" ""
			(at 0 0 180)
			(layer "F.Fab")
			(effects
				(font
					(size 1.27 1.27)
				)
			)
		)
		(duplicate_pad_numbers_are_jumpers no)
		(fp_line
			(start 0.7874 0.4064)
			(end -0.7874 0.4064)
			(stroke
				(width 0.1524)
				(type default)
			)
			(layer "F.SilkS")
		)
		(fp_line
			(start 0.7874 -0.4064)
			(end 0.7874 0.4064)
			(stroke
				(width 0.1524)
				(type default)
			)
			(layer "F.SilkS")
		)
		(fp_line
			(start -0.7874 0.4064)
			(end -0.7874 -0.4064)
			(stroke
				(width 0.1524)
				(type default)
			)
			(layer "F.SilkS")
		)
		(fp_line
			(start -0.7874 -0.4064)
			(end 0.7874 -0.4064)
			(stroke
				(width 0.1524)
				(type default)
			)
			(layer "F.SilkS")
		)
		(fp_line
			(start 0.67945 0.3048)
			(end 0.120396 0.3048)
			(stroke
				(width 0.1)
				(type default)
			)
			(layer "F.Fab")
		)
		(fp_line
			(start 0.67945 -0.3048)
			(end 0.67945 0.3048)
			(stroke
				(width 0.1)
				(type default)
			)
			(layer "F.Fab")
		)
		(fp_line
			(start 0.12065 -0.2794)
			(end 0.12065 -0.3048)
			(stroke
				(width 0.1)
				(type default)
			)
			(layer "F.Fab")
		)
		(fp_line
			(start 0.12065 -0.3048)
			(end 0.67945 -0.3048)
			(stroke
				(width 0.1)
				(type default)
			)
			(layer "F.Fab")
		)
		(fp_line
			(start 0.120396 0.3048)
			(end 0.120396 0.2794)
			(stroke
				(width 0.1)
				(type default)
			)
			(layer "F.Fab")
		)
		(fp_line
			(start 0.120396 0.2794)
			(end -0.12065 0.2794)
			(stroke
				(width 0.1)
				(type default)
			)
			(layer "F.Fab")
		)
		(fp_line
			(start -0.12065 0.3048)
			(end -0.67945 0.3048)
			(stroke
				(width 0.1)
				(type default)
			)
			(layer "F.Fab")
		)
		(fp_line
			(start -0.12065 0.2794)
			(end -0.12065 0.3048)
			(stroke
				(width 0.1)
				(type default)
			)
			(layer "F.Fab")
		)
		(fp_line
			(start -0.12065 -0.2794)
			(end 0.12065 -0.2794)
			(stroke
				(width 0.1)
				(type default)
			)
			(layer "F.Fab")
		)
		(fp_line
			(start -0.12065 -0.305054)
			(end -0.12065 -0.2794)
			(stroke
				(width 0.1)
				(type default)
			)
			(layer "F.Fab")
		)
		(fp_line
			(start -0.67945 0.3048)
			(end -0.67945 -0.305054)
			(stroke
				(width 0.1)
				(type default)
			)
			(layer "F.Fab")
		)
		(fp_line
			(start -0.67945 -0.305054)
			(end -0.12065 -0.305054)
			(stroke
				(width 0.1)
				(type default)
			)
			(layer "F.Fab")
		)
		(pad "1" smd rect
			(at -0.40005 0)
			(size 0.4572 0.508)
			(layers "F.Cu" "F.Mask" "F.Paste")
			(net "P12V_LED_FAN6")
		)
		(pad "2" smd rect
			(at 0.40005 0)
			(size 0.4572 0.508)
			(layers "F.Cu" "F.Mask" "F.Paste")
			(net "FAN_6_OK_LED_R_N")
		)
	)
	(footprint ""
		(layer "F.Cu")
		(at 29.0322 -58.70194 90)
		(property "Reference" "ME6"
			(at 0 0 90)
			(layer "F.SilkS")
			(hide yes)
			(effects
				(font
					(size 1.27 1.27)
				)
			)
		)
		(property "Value" ""
			(at 0 0 90)
			(layer "F.Fab")
			(effects
				(font
					(size 1.27 1.27)
				)
			)
		)
		(duplicate_pad_numbers_are_jumpers no)
	)
	(footprint ""
		(layer "F.Cu")
		(at 43.053 -98.806 180)
		(property "Reference" "C2122"
			(at 0 0 180)
			(layer "F.SilkS")
			(hide yes)
			(effects
				(font
					(size 1.27 1.27)
				)
			)
		)
		(property "Value" ""
			(at 0 0 180)
			(layer "F.Fab")
			(effects
				(font
					(size 1.27 1.27)
				)
			)
		)
		(duplicate_pad_numbers_are_jumpers no)
		(fp_line
			(start 1.2954 0.5842)
			(end -1.2954 0.5842)
			(stroke
				(width 0.1524)
				(type default)
			)
			(layer "F.SilkS")
		)
		(fp_line
			(start 1.2954 -0.5842)
			(end 1.2954 0.5842)
			(stroke
				(width 0.1524)
				(type default)
			)
			(layer "F.SilkS")
		)
		(fp_line
			(start -1.2954 0.5842)
			(end -1.2954 -0.5842)
			(stroke
				(width 0.1524)
				(type default)
			)
			(layer "F.SilkS")
		)
		(fp_line
			(start -1.2954 -0.5842)
			(end 1.2954 -0.5842)
			(stroke
				(width 0.1524)
				(type default)
			)
			(layer "F.SilkS")
		)
		(fp_line
			(start 1.1938 0.4064)
			(end 0.8636 0.4064)
			(stroke
				(width 0.1)
				(type default)
			)
			(layer "F.Fab")
		)
		(fp_line
			(start 1.1938 -0.4064)
			(end 1.1938 0.4064)
			(stroke
				(width 0.1)
				(type default)
			)
			(layer "F.Fab")
		)
		(fp_line
			(start 0.8636 0.4572)
			(end -0.8636 0.4572)
			(stroke
				(width 0.1)
				(type default)
			)
			(layer "F.Fab")
		)
		(fp_line
			(start 0.8636 0.4064)
			(end 0.8636 0.4572)
			(stroke
				(width 0.1)
				(type default)
			)
			(layer "F.Fab")
		)
		(fp_line
			(start 0.8636 -0.4064)
			(end 1.1938 -0.4064)
			(stroke
				(width 0.1)
				(type default)
			)
			(layer "F.Fab")
		)
		(fp_line
			(start 0.8636 -0.4572)
			(end 0.8636 -0.4064)
			(stroke
				(width 0.1)
				(type default)
			)
			(layer "F.Fab")
		)
		(fp_line
			(start -0.8636 0.4572)
			(end -0.8636 0.4064)
			(stroke
				(width 0.1)
				(type default)
			)
			(layer "F.Fab")
		)
		(fp_line
			(start -0.8636 0.4064)
			(end -1.1938 0.4064)
			(stroke
				(width 0.1)
				(type default)
			)
			(layer "F.Fab")
		)
		(fp_line
			(start -0.8636 -0.4064)
			(end -0.8636 -0.4572)
			(stroke
				(width 0.1)
				(type default)
			)
			(layer "F.Fab")
		)
		(fp_line
			(start -0.8636 -0.4572)
			(end 0.8636 -0.4572)
			(stroke
				(width 0.1)
				(type default)
			)
			(layer "F.Fab")
		)
		(fp_line
			(start -1.1938 0.4064)
			(end -1.1938 -0.4064)
			(stroke
				(width 0.1)
				(type default)
			)
			(layer "F.Fab")
		)
		(fp_line
			(start -1.1938 -0.4064)
			(end -0.8636 -0.4064)
			(stroke
				(width 0.1)
				(type default)
			)
			(layer "F.Fab")
		)
		(pad "1" smd rect
			(at -0.7366 0 90)
			(size 0.7112 0.8128)
			(layers "F.Cu" "F.Mask" "F.Paste")
			(net "U407_D1")
		)
		(pad "2" smd rect
			(at 0.7366 0 90)
			(size 0.7112 0.8128)
			(layers "F.Cu" "F.Mask" "F.Paste")
			(net "GND")
		)
	)
	(footprint ""
		(layer "F.Cu")
		(at 13.335 -169.291 180)
		(property "Reference" "R5503"
			(at 0 0 180)
			(layer "F.SilkS")
			(hide yes)
			(effects
				(font
					(size 1.27 1.27)
				)
			)
		)
		(property "Value" ""
			(at 0 0 180)
			(layer "F.Fab")
			(effects
				(font
					(size 1.27 1.27)
				)
			)
		)
		(duplicate_pad_numbers_are_jumpers no)
		(fp_line
			(start 0.7874 0.4064)
			(end -0.7874 0.4064)
			(stroke
				(width 0.1524)
				(type default)
			)
			(layer "F.SilkS")
		)
		(fp_line
			(start 0.7874 -0.4064)
			(end 0.7874 0.4064)
			(stroke
				(width 0.1524)
				(type default)
			)
			(layer "F.SilkS")
		)
		(fp_line
			(start -0.7874 0.4064)
			(end -0.7874 -0.4064)
			(stroke
				(width 0.1524)
				(type default)
			)
			(layer "F.SilkS")
		)
		(fp_line
			(start -0.7874 -0.4064)
			(end 0.7874 -0.4064)
			(stroke
				(width 0.1524)
				(type default)
			)
			(layer "F.SilkS")
		)
		(fp_line
			(start 0.67945 0.3048)
			(end 0.120396 0.3048)
			(stroke
				(width 0.1)
				(type default)
			)
			(layer "F.Fab")
		)
		(fp_line
			(start 0.67945 -0.3048)
			(end 0.67945 0.3048)
			(stroke
				(width 0.1)
				(type default)
			)
			(layer "F.Fab")
		)
		(fp_line
			(start 0.12065 -0.2794)
			(end 0.12065 -0.3048)
			(stroke
				(width 0.1)
				(type default)
			)
			(layer "F.Fab")
		)
		(fp_line
			(start 0.12065 -0.3048)
			(end 0.67945 -0.3048)
			(stroke
				(width 0.1)
				(type default)
			)
			(layer "F.Fab")
		)
		(fp_line
			(start 0.120396 0.3048)
			(end 0.120396 0.2794)
			(stroke
				(width 0.1)
				(type default)
			)
			(layer "F.Fab")
		)
		(fp_line
			(start 0.120396 0.2794)
			(end -0.12065 0.2794)
			(stroke
				(width 0.1)
				(type default)
			)
			(layer "F.Fab")
		)
		(fp_line
			(start -0.12065 0.3048)
			(end -0.67945 0.3048)
			(stroke
				(width 0.1)
				(type default)
			)
			(layer "F.Fab")
		)
		(fp_line
			(start -0.12065 0.2794)
			(end -0.12065 0.3048)
			(stroke
				(width 0.1)
				(type default)
			)
			(layer "F.Fab")
		)
		(fp_line
			(start -0.12065 -0.2794)
			(end 0.12065 -0.2794)
			(stroke
				(width 0.1)
				(type default)
			)
			(layer "F.Fab")
		)
		(fp_line
			(start -0.12065 -0.305054)
			(end -0.12065 -0.2794)
			(stroke
				(width 0.1)
				(type default)
			)
			(layer "F.Fab")
		)
		(fp_line
			(start -0.67945 0.3048)
			(end -0.67945 -0.305054)
			(stroke
				(width 0.1)
				(type default)
			)
			(layer "F.Fab")
		)
		(fp_line
			(start -0.67945 -0.305054)
			(end -0.12065 -0.305054)
			(stroke
				(width 0.1)
				(type default)
			)
			(layer "F.Fab")
		)
		(pad "1" smd circle
			(at -0.40005 0 180)
			(size 0 0)
			(layers "F.Cu" "F.Mask" "F.Paste")
			(net "P3V3_AUX")
		)
		(pad "2" smd circle
			(at 0.40005 0 180)
			(size 0 0)
			(layers "F.Cu" "F.Mask" "F.Paste")
			(net "FAN_4_PRESENT_N")
		)
	)
	(footprint ""
		(layer "F.Cu")
		(at 46.355 -167.513)
		(property "Reference" "R5116"
			(at 0 0 0)
			(layer "F.SilkS")
			(hide yes)
			(effects
				(font
					(size 1.27 1.27)
				)
			)
		)
		(property "Value" ""
			(at 0 0 0)
			(layer "F.Fab")
			(effects
				(font
					(size 1.27 1.27)
				)
			)
		)
		(duplicate_pad_numbers_are_jumpers no)
		(fp_line
			(start -0.7874 -0.4064)
			(end 0.7874 -0.4064)
			(stroke
				(width 0.1524)
				(type default)
			)
			(layer "F.SilkS")
		)
		(fp_line
			(start -0.7874 0.4064)
			(end -0.7874 -0.4064)
			(stroke
				(width 0.1524)
				(type default)
			)
			(layer "F.SilkS")
		)
		(fp_line
			(start 0.7874 -0.4064)
			(end 0.7874 0.4064)
			(stroke
				(width 0.1524)
				(type default)
			)
			(layer "F.SilkS")
		)
		(fp_line
			(start 0.7874 0.4064)
			(end -0.7874 0.4064)
			(stroke
				(width 0.1524)
				(type default)
			)
			(layer "F.SilkS")
		)
		(fp_line
			(start -0.67945 -0.305054)
			(end -0.12065 -0.305054)
			(stroke
				(width 0.1)
				(type default)
			)
			(layer "F.Fab")
		)
		(fp_line
			(start -0.67945 0.3048)
			(end -0.67945 -0.305054)
			(stroke
				(width 0.1)
				(type default)
			)
			(layer "F.Fab")
		)
		(fp_line
			(start -0.12065 -0.305054)
			(end -0.12065 -0.2794)
			(stroke
				(width 0.1)
				(type default)
			)
			(layer "F.Fab")
		)
		(fp_line
			(start -0.12065 -0.2794)
			(end 0.12065 -0.2794)
			(stroke
				(width 0.1)
				(type default)
			)
			(layer "F.Fab")
		)
		(fp_line
			(start -0.12065 0.2794)
			(end -0.12065 0.3048)
			(stroke
				(width 0.1)
				(type default)
			)
			(layer "F.Fab")
		)
		(fp_line
			(start -0.12065 0.3048)
			(end -0.67945 0.3048)
			(stroke
				(width 0.1)
				(type default)
			)
			(layer "F.Fab")
		)
		(fp_line
			(start 0.120396 0.2794)
			(end -0.12065 0.2794)
			(stroke
				(width 0.1)
				(type default)
			)
			(layer "F.Fab")
		)
		(fp_line
			(start 0.120396 0.3048)
			(end 0.120396 0.2794)
			(stroke
				(width 0.1)
				(type default)
			)
			(layer "F.Fab")
		)
		(fp_line
			(start 0.12065 -0.3048)
			(end 0.67945 -0.3048)
			(stroke
				(width 0.1)
				(type default)
			)
			(layer "F.Fab")
		)
		(fp_line
			(start 0.12065 -0.2794)
			(end 0.12065 -0.3048)
			(stroke
				(width 0.1)
				(type default)
			)
			(layer "F.Fab")
		)
		(fp_line
			(start 0.67945 -0.3048)
			(end 0.67945 0.3048)
			(stroke
				(width 0.1)
				(type default)
			)
			(layer "F.Fab")
		)
		(fp_line
			(start 0.67945 0.3048)
			(end 0.120396 0.3048)
			(stroke
				(width 0.1)
				(type default)
			)
			(layer "F.Fab")
		)
		(pad "1" smd circle
			(at -0.40005 0)
			(size 0 0)
			(layers "F.Cu" "F.Mask" "F.Paste")
			(net "PCA9552_MB1_A1")
		)
		(pad "2" smd circle
			(at 0.40005 0)
			(size 0 0)
			(layers "F.Cu" "F.Mask" "F.Paste")
			(net "GND")
		)
	)
	(footprint ""
		(layer "F.Cu")
		(at 19.431 -136.017 -90)
		(property "Reference" "R4850"
			(at 0 0 270)
			(layer "F.SilkS")
			(hide yes)
			(effects
				(font
					(size 1.27 1.27)
				)
			)
		)
		(property "Value" ""
			(at 0 0 270)
			(layer "F.Fab")
			(effects
				(font
					(size 1.27 1.27)
				)
			)
		)
		(duplicate_pad_numbers_are_jumpers no)
		(fp_line
			(start -0.7874 0.4064)
			(end -0.7874 -0.4064)
			(stroke
				(width 0.1524)
				(type default)
			)
			(layer "F.SilkS")
		)
		(fp_line
			(start 0.7874 0.4064)
			(end -0.7874 0.4064)
			(stroke
				(width 0.1524)
				(type default)
			)
			(layer "F.SilkS")
		)
		(fp_line
			(start -0.7874 -0.4064)
			(end 0.7874 -0.4064)
			(stroke
				(width 0.1524)
				(type default)
			)
			(layer "F.SilkS")
		)
		(fp_line
			(start 0.7874 -0.4064)
			(end 0.7874 0.4064)
			(stroke
				(width 0.1524)
				(type default)
			)
			(layer "F.SilkS")
		)
		(fp_line
			(start -0.67945 0.3048)
			(end -0.67945 -0.305054)
			(stroke
				(width 0.1)
				(type default)
			)
			(layer "F.Fab")
		)
		(fp_line
			(start -0.12065 0.3048)
			(end -0.67945 0.3048)
			(stroke
				(width 0.1)
				(type default)
			)
			(layer "F.Fab")
		)
		(fp_line
			(start 0.120396 0.3048)
			(end 0.120396 0.2794)
			(stroke
				(width 0.1)
				(type default)
			)
			(layer "F.Fab")
		)
		(fp_line
			(start 0.67945 0.3048)
			(end 0.120396 0.3048)
			(stroke
				(width 0.1)
				(type default)
			)
			(layer "F.Fab")
		)
		(fp_line
			(start -0.12065 0.2794)
			(end -0.12065 0.3048)
			(stroke
				(width 0.1)
				(type default)
			)
			(layer "F.Fab")
		)
		(fp_line
			(start 0.120396 0.2794)
			(end -0.12065 0.2794)
			(stroke
				(width 0.1)
				(type default)
			)
			(layer "F.Fab")
		)
		(fp_line
			(start -0.12065 -0.2794)
			(end 0.12065 -0.2794)
			(stroke
				(width 0.1)
				(type default)
			)
			(layer "F.Fab")
		)
		(fp_line
			(start 0.12065 -0.2794)
			(end 0.12065 -0.3048)
			(stroke
				(width 0.1)
				(type default)
			)
			(layer "F.Fab")
		)
		(fp_line
			(start 0.12065 -0.3048)
			(end 0.67945 -0.3048)
			(stroke
				(width 0.1)
				(type default)
			)
			(layer "F.Fab")
		)
		(fp_line
			(start 0.67945 -0.3048)
			(end 0.67945 0.3048)
			(stroke
				(width 0.1)
				(type default)
			)
			(layer "F.Fab")
		)
		(fp_line
			(start -0.67945 -0.305054)
			(end -0.12065 -0.305054)
			(stroke
				(width 0.1)
				(type default)
			)
			(layer "F.Fab")
		)
		(fp_line
			(start -0.12065 -0.305054)
			(end -0.12065 -0.2794)
			(stroke
				(width 0.1)
				(type default)
			)
			(layer "F.Fab")
		)
		(pad "1" smd circle
			(at -0.40005 0 270)
			(size 0 0)
			(layers "F.Cu" "F.Mask" "F.Paste")
			(net "GND")
		)
		(pad "2" smd circle
			(at 0.40005 0 270)
			(size 0 0)
			(layers "F.Cu" "F.Mask" "F.Paste")
			(net "MAX31790_U330_ADD0")
		)
	)
)
